FILE_TYPE = MULTI_PHYS_TABLE;
PART 'LED'
{========================================================================================}
:COLOR    | PACK_TYPE | MATERIAL | PART_NUMBER    = ENVCOMP                  | PART_NUMBER   | JEDEC_TYPE   | CLASS | DESCRIPTION                                          | HEIGHT     | COMPONENT_TYPE | LEAD_LENGTH | LPID    | SPEED_URL                                                                                                                        | STATUS        | RPL   | AML | BUS_UNIT      | DAYS  ;
{========================================================================================}
'YELLOW' | '1NCLF'   | 'IC'     | 'C96565-003'(!) = 'YES;YES;UNK;UNK;ok;VLD' | 'C96565-003'  | 'SLEDA1208A' | 'IC'  | 'LED,SM,YELLOW,RA,1.00,RD,1'                         | '0.045 IN' | 'SMTOTHER'     | ''          | '1793'  | 'http://speed.intel.com:8081/speed/module/pdm/item/pdm_item_detail_direct.asp?item_cde=C96565-003&item_rev=01&url_param=unused'  | 'Design'      | 'NO'  | '2' | 'SMO_BOARDS'  | '???'
'YELLOW' | '1NCLF'   | 'EMPTY'  | 'C96565-003'(!) = 'YES;YES;UNK;UNK;ok;VLD' | 'C96565-003'  | 'SLEDA1208A' | 'IO'  | 'LED,SM,YELLOW,RA,1.00,RD,1'                         | '0.045 IN' | 'SMTOTHER'     | ''          | '1793'  | 'http://speed.intel.com:8081/speed/module/pdm/item/pdm_item_detail_direct.asp?item_cde=C96565-003&item_rev=01&url_param=unused'  | 'Design'      | 'NO'  | '2' | 'SMO_BOARDS'  | '???'
'GREEN'  | '1NCLF'   | 'IC'     | 'C96565-011'(!) = 'YES;YES;UNK;UNK;ok;VLD' | 'C96565-011'  | 'SLEDA1208A' | 'IC'  | 'LED,3010,SM,GRN,RA,2.00,RC,1'                       | '0.046 IN' | 'SMTOTHER'     | ''          | '1793'  | 'http://speed.intel.com:8081/speed/module/pdm/item/pdm_item_detail_direct.asp?item_cde=C96565-011&item_rev=01&url_param=unused'  | 'Design'      | 'YES' | '1' | 'SMO_BOARDS'  | '???'
'GREEN'  | '1NCLF'   | 'EMPTY'  | 'C96565-011'(!) = 'YES;YES;UNK;UNK;ok;VLD' | 'C96565-011'  | 'SLEDA1208A' | 'IO'  | 'LED,3010,SM,GRN,RA,2.00,RC,1'                       | '0.046 IN' | 'SMTOTHER'     | ''          | '1793'  | 'http://speed.intel.com:8081/speed/module/pdm/item/pdm_item_detail_direct.asp?item_cde=C96565-011&item_rev=01&url_param=unused'  | 'Design'      | 'YES' | '1' | 'SMO_BOARDS'  | '???'
'BLUE'   | '1NC'     | 'IC'     | 'C96565-012'(!) = 'YES;YES;UNK;UNK;ok;VLD' | 'C96565-012'  | 'SLEDA1208A' | 'IC'  | 'LED,3010,SM,BLU,RA,1.00,RD,1'                       | '0.045 IN' | 'SMTOTHER'     | ''          | '1793'  | 'http://speed.intel.com:8081/speed/module/pdm/item/pdm_item_detail_direct.asp?item_cde=C96565-012&item_rev=01&url_param=unused'  | 'Design'      | 'YES' | '1' | 'SMO_BOARDS'  | '???'
'BLUE'   | '1NC'     | 'EMPTY'  | 'C96565-012'(!) = 'YES;YES;UNK;UNK;ok;VLD' | 'C96565-012'  | 'SLEDA1208A' | 'IO'  | 'LED,3010,SM,BLU,RA,1.00,RD,1'                       | '0.045 IN' | 'SMTOTHER'     | ''          | '1793'  | 'http://speed.intel.com:8081/speed/module/pdm/item/pdm_item_detail_direct.asp?item_cde=C96565-012&item_rev=01&url_param=unused'  | 'Design'      | 'YES' | '1' | 'SMO_BOARDS'  | '???'
'RED'    | 'A1'      | 'IC'     | 'D14725-005'(!) = 'YES;YES;YES;UNK;ok;VLD' | 'D14725-005'  | 'SLEDR0603A' | 'IC'  | 'LED,SM,RED,V,1.00,RC,1'                             | '0.033 IN' | 'CHIP0603'     | ''          | '553'   | 'http://speed.intel.com:8081/speed/module/pdm/item/pdm_item_detail_direct.asp?item_cde=D14725-005&item_rev=01&url_param=unused'  | 'Approved'    | 'YES' | '2' | 'SMO_BOARDS'  | '56' 
'RED'    | 'A1'      | 'EMPTY'  | 'D14725-005'(!) = 'YES;YES;YES;UNK;ok;VLD' | 'D14725-005'  | 'SLEDR0603A' | 'IO'  | 'LED,SM,RED,V,1.00,RC,1'                             | '0.033 IN' | 'CHIP0603'     | ''          | '553'   | 'http://speed.intel.com:8081/speed/module/pdm/item/pdm_item_detail_direct.asp?item_cde=D14725-005&item_rev=01&url_param=unused'  | 'Approved'    | 'YES' | '2' | 'SMO_BOARDS'  | '56' 
'GREEN'  | 'A1LF'    | 'IC'     | 'D14725-022'(!) = 'YES;YES;YES;UNK;ok;VLD' | 'D14725-022'  | 'SLEDR0603A' | 'IC'  | 'LED,1608,SM,GRN,V,1.00,RC,1'                        | '0.035 IN' | 'CHIP0603'     | ''          | '553'   | 'http://speed.intel.com:8081/speed/module/pdm/item/pdm_item_detail_direct.asp?item_cde=D14725-022&item_rev=01&url_param=unused'  | 'Conditional' | 'YES' | '3' | 'SMO_BOARDS'  | '???'
'GREEN'  | 'A1LF'    | 'EMPTY'  | 'D14725-022'(!) = 'YES;YES;YES;UNK;ok;VLD' | 'D14725-022'  | 'SLEDR0603A' | 'IO'  | 'LED,1608,SM,GRN,V,1.00,RC,1'                        | '0.035 IN' | 'CHIP0603'     | ''          | '553'   | 'http://speed.intel.com:8081/speed/module/pdm/item/pdm_item_detail_direct.asp?item_cde=D14725-022&item_rev=01&url_param=unused'  | 'Conditional' | 'YES' | '3' | 'SMO_BOARDS'  | '???'
'GREEN'  | 'A1LF'    | 'IC'     | 'C97278-010'(!) = 'YES;YES;UNK;UNK;ok;VLD' | 'C97278-010'  | 'SLEDR0805B' | 'IC'  | 'LED,2012,SM,GRN,V,1.00,RC,1'                        | '0.033 IN' | 'CHIP0805'     | ''          | '557'   | 'http://speed.intel.com:8081/speed/module/pdm/item/pdm_item_detail_direct.asp?item_cde=C97278-010&item_rev=01&url_param=unused'  | 'Design'      | 'YES' | '1' | 'SMO_BOARDS'  | '???'
'GREEN'  | 'A1LF'    | 'EMPTY'  | 'C97278-010'(!) = 'YES;YES;UNK;UNK;ok;VLD' | 'C97278-010'  | 'SLEDR0805B' | 'IO'  | 'LED,2012,SM,GRN,V,1.00,RC,1'                        | '0.033 IN' | 'CHIP0805'     | ''          | '557'   | 'http://speed.intel.com:8081/speed/module/pdm/item/pdm_item_detail_direct.asp?item_cde=C97278-010&item_rev=01&url_param=unused'  | 'Design'      | 'YES' | '1' | 'SMO_BOARDS'  | '???'
{Entries Below was replaced with new Pack type}
{new pack type (all the parts below have Anode on Pin#1 }
END_PART
END.
